# S9S_MB_2U (Grand Teton) — schematic netlist excerpt (pin names and nets, part order shuffled) for the footprints in the layout excerpt that follows; sources: Cadence DE-HDL packaged netlist, KiCad conversion of 03242023_DA0F0TMBIJ0_F0T_Motherboard_J_brd_V01_OCP.brd

R2924  Q_RES  49.9 1% CHIP  pkg 0402LF  page 151 : A = RST_SWB_BIC_BUF_R_N ; B = RST_SWB_BIC_BUF_N
R1100  Q_RES  33.2 1% CHIP  pkg 0402LF  page 214 : A = CLK_25M_OSC_FPGA_R ; B = CLK_25M_OSC_MAIN_FPGA

(kicad_pcb
	(version 20260206)
	(generator "pcbnew")
	(generator_version "10.0")
	(general
		(thickness 1.6)
		(legacy_teardrops no)
	)
	(paper "A4")
	(title_block
		(title "03242023_DA0F0TMBIJ0_F0T_Motherboard_J_brd_V01_OCP.brd")
		(comment 1 "Grand Teton / footprints 1633-1634 of 6105")
	)
	(layers
		(0 "F.Cu" signal "TOP")
		(4 "In1.Cu" signal "GND")
		(6 "In2.Cu" signal "IN1")
		(8 "In3.Cu" signal "GND1")
		(10 "In4.Cu" signal "IN2")
		(12 "In5.Cu" signal "GND2")
		(14 "In6.Cu" signal "IN3")
		(16 "In7.Cu" signal "GND3")
		(18 "In8.Cu" signal "VCC")
		(20 "In9.Cu" signal "VCC1")
		(22 "In10.Cu" signal "GND4")
		(24 "In11.Cu" signal "IN4")
		(26 "In12.Cu" signal "GND5")
		(28 "In13.Cu" signal "IN5")
		(30 "In14.Cu" signal "GND6")
		(32 "In15.Cu" signal "IN6")
		(34 "In16.Cu" signal "GND7")
		(2 "B.Cu" signal "BOTTOM")
		(9 "F.Adhes" user "F.Adhesive")
		(11 "B.Adhes" user "B.Adhesive")
		(13 "F.Paste" user "Package Geometry/Pastemask Top")
		(15 "B.Paste" user "Package Geometry/Pastemask Bottom")
		(5 "F.SilkS" user "Ref Des/Silkscreen Top")
		(7 "B.SilkS" user "Ref Des/Silkscreen Bottom")
		(1 "F.Mask" user "Board Geometry/Soldermask Top")
		(3 "B.Mask" user "Board Geometry/Soldermask Bottom")
		(17 "Dwgs.User" user "User.Drawings")
		(19 "Cmts.User" user "User.Comments")
		(21 "Eco1.User" user "User.Eco1")
		(23 "Eco2.User" user "User.Eco2")
		(25 "Edge.Cuts" user "Board Geometry/Outline")
		(27 "Margin" user)
		(31 "F.CrtYd" user "Package Geometry/Place Bound Top")
		(29 "B.CrtYd" user "Package Geometry/Place Bound Bottom")
		(35 "F.Fab" user "Ref Des/Assembly Top")
		(33 "B.Fab" user "Ref Des/Assembly Bottom")
	)
	(footprint ""
		(layer "F.Cu")
		(at 192.58788 -112.613948 90)
		(property "Reference" "R1100"
			(at 0 0 90)
			(layer "F.SilkS")
			(hide yes)
			(effects
				(font
					(size 1.27 1.27)
				)
			)
		)
		(property "Value" ""
			(at 0 0 90)
			(layer "F.Fab")
			(effects
				(font
					(size 1.27 1.27)
				)
			)
		)
		(duplicate_pad_numbers_are_jumpers no)
		(fp_line
			(start 0.7874 -0.4064)
			(end 0.7874 0.4064)
			(stroke
				(width 0.1524)
				(type default)
			)
			(layer "F.SilkS")
		)
		(fp_line
			(start -0.7874 -0.4064)
			(end 0.7874 -0.4064)
			(stroke
				(width 0.1524)
				(type default)
			)
			(layer "F.SilkS")
		)
		(fp_line
			(start 0.7874 0.4064)
			(end -0.7874 0.4064)
			(stroke
				(width 0.1524)
				(type default)
			)
			(layer "F.SilkS")
		)
		(fp_line
			(start -0.7874 0.4064)
			(end -0.7874 -0.4064)
			(stroke
				(width 0.1524)
				(type default)
			)
			(layer "F.SilkS")
		)
		(fp_line
			(start -0.12065 -0.305054)
			(end -0.12065 -0.2794)
			(stroke
				(width 0.1)
				(type default)
			)
			(layer "F.Fab")
		)
		(fp_line
			(start -0.67945 -0.305054)
			(end -0.12065 -0.305054)
			(stroke
				(width 0.1)
				(type default)
			)
			(layer "F.Fab")
		)
		(fp_line
			(start 0.67945 -0.3048)
			(end 0.67945 0.3048)
			(stroke
				(width 0.1)
				(type default)
			)
			(layer "F.Fab")
		)
		(fp_line
			(start 0.12065 -0.3048)
			(end 0.67945 -0.3048)
			(stroke
				(width 0.1)
				(type default)
			)
			(layer "F.Fab")
		)
		(fp_line
			(start 0.12065 -0.2794)
			(end 0.12065 -0.3048)
			(stroke
				(width 0.1)
				(type default)
			)
			(layer "F.Fab")
		)
		(fp_line
			(start -0.12065 -0.2794)
			(end 0.12065 -0.2794)
			(stroke
				(width 0.1)
				(type default)
			)
			(layer "F.Fab")
		)
		(fp_line
			(start 0.120396 0.2794)
			(end -0.12065 0.2794)
			(stroke
				(width 0.1)
				(type default)
			)
			(layer "F.Fab")
		)
		(fp_line
			(start -0.12065 0.2794)
			(end -0.12065 0.3048)
			(stroke
				(width 0.1)
				(type default)
			)
			(layer "F.Fab")
		)
		(fp_line
			(start 0.67945 0.3048)
			(end 0.120396 0.3048)
			(stroke
				(width 0.1)
				(type default)
			)
			(layer "F.Fab")
		)
		(fp_line
			(start 0.120396 0.3048)
			(end 0.120396 0.2794)
			(stroke
				(width 0.1)
				(type default)
			)
			(layer "F.Fab")
		)
		(fp_line
			(start -0.12065 0.3048)
			(end -0.67945 0.3048)
			(stroke
				(width 0.1)
				(type default)
			)
			(layer "F.Fab")
		)
		(fp_line
			(start -0.67945 0.3048)
			(end -0.67945 -0.305054)
			(stroke
				(width 0.1)
				(type default)
			)
			(layer "F.Fab")
		)
		(pad "1" smd circle
			(at -0.40005 0 90)
			(size 0 0)
			(layers "F.Cu" "F.Mask" "F.Paste")
			(net "CLK_25M_OSC_FPGA_R")
		)
		(pad "2" smd circle
			(at 0.40005 0 90)
			(size 0 0)
			(layers "F.Cu" "F.Mask" "F.Paste")
			(net "CLK_25M_OSC_MAIN_FPGA")
		)
	)
	(footprint ""
		(layer "F.Cu")
		(at 176.17948 -423.382948)
		(property "Reference" "R2924"
			(at 0 0 0)
			(layer "F.SilkS")
			(hide yes)
			(effects
				(font
					(size 1.27 1.27)
				)
			)
		)
		(property "Value" ""
			(at 0 0 0)
			(layer "F.Fab")
			(effects
				(font
					(size 1.27 1.27)
				)
			)
		)
		(duplicate_pad_numbers_are_jumpers no)
		(fp_line
			(start -0.7874 -0.4064)
			(end 0.7874 -0.4064)
			(stroke
				(width 0.1524)
				(type default)
			)
			(layer "F.SilkS")
		)
		(fp_line
			(start -0.7874 0.4064)
			(end -0.7874 -0.4064)
			(stroke
				(width 0.1524)
				(type default)
			)
			(layer "F.SilkS")
		)
		(fp_line
			(start 0.7874 -0.4064)
			(end 0.7874 0.4064)
			(stroke
				(width 0.1524)
				(type default)
			)
			(layer "F.SilkS")
		)
		(fp_line
			(start 0.7874 0.4064)
			(end -0.7874 0.4064)
			(stroke
				(width 0.1524)
				(type default)
			)
			(layer "F.SilkS")
		)
		(fp_line
			(start -0.67945 -0.305054)
			(end -0.12065 -0.305054)
			(stroke
				(width 0.1)
				(type default)
			)
			(layer "F.Fab")
		)
		(fp_line
			(start -0.67945 0.3048)
			(end -0.67945 -0.305054)
			(stroke
				(width 0.1)
				(type default)
			)
			(layer "F.Fab")
		)
		(fp_line
			(start -0.12065 -0.305054)
			(end -0.12065 -0.2794)
			(stroke
				(width 0.1)
				(type default)
			)
			(layer "F.Fab")
		)
		(fp_line
			(start -0.12065 -0.2794)
			(end 0.12065 -0.2794)
			(stroke
				(width 0.1)
				(type default)
			)
			(layer "F.Fab")
		)
		(fp_line
			(start -0.12065 0.2794)
			(end -0.12065 0.3048)
			(stroke
				(width 0.1)
				(type default)
			)
			(layer "F.Fab")
		)
		(fp_line
			(start -0.12065 0.3048)
			(end -0.67945 0.3048)
			(stroke
				(width 0.1)
				(type default)
			)
			(layer "F.Fab")
		)
		(fp_line
			(start 0.120396 0.2794)
			(end -0.12065 0.2794)
			(stroke
				(width 0.1)
				(type default)
			)
			(layer "F.Fab")
		)
		(fp_line
			(start 0.120396 0.3048)
			(end 0.120396 0.2794)
			(stroke
				(width 0.1)
				(type default)
			)
			(layer "F.Fab")
		)
		(fp_line
			(start 0.12065 -0.3048)
			(end 0.67945 -0.3048)
			(stroke
				(width 0.1)
				(type default)
			)
			(layer "F.Fab")
		)
		(fp_line
			(start 0.12065 -0.2794)
			(end 0.12065 -0.3048)
			(stroke
				(width 0.1)
				(type default)
			)
			(layer "F.Fab")
		)
		(fp_line
			(start 0.67945 -0.3048)
			(end 0.67945 0.3048)
			(stroke
				(width 0.1)
				(type default)
			)
			(layer "F.Fab")
		)
		(fp_line
			(start 0.67945 0.3048)
			(end 0.120396 0.3048)
			(stroke
				(width 0.1)
				(type default)
			)
			(layer "F.Fab")
		)
		(pad "1" smd circle
			(at -0.40005 0)
			(size 0 0)
			(layers "F.Cu" "F.Mask" "F.Paste")
			(net "RST_SWB_BIC_BUF_R_N")
		)
		(pad "2" smd circle
			(at 0.40005 0)
			(size 0 0)
			(layers "F.Cu" "F.Mask" "F.Paste")
			(net "RST_SWB_BIC_BUF_N")
		)
	)
)
